(kicad_pcb
	(version 20260206)
	(generator "pcbnew")
	(generator_version "10.0")
	(general
		(thickness 1.6)
		(legacy_teardrops no)
	)
	(paper "A4")
	(title_block
		(title "Wiwynn_Tioga_Pass_MB.brd")
		(comment 1 "Tioga Pass / footprints 392-399 of 4770")
	)
	(layers
		(0 "F.Cu" signal "TOP")
		(4 "In1.Cu" signal "L2GND")
		(6 "In2.Cu" signal "L3")
		(8 "In3.Cu" signal "L4GND")
		(10 "In4.Cu" signal "L5")
		(12 "In5.Cu" signal "L6GND")
		(14 "In6.Cu" signal "L7VCC")
		(16 "In7.Cu" signal "L8VCC")
		(18 "In8.Cu" signal "L9GND")
		(20 "In9.Cu" signal "L10")
		(22 "In10.Cu" signal "L11GND")
		(24 "In11.Cu" signal "L12")
		(26 "In12.Cu" signal "L13GND")
		(2 "B.Cu" signal "BOTTOM")
		(9 "F.Adhes" user "F.Adhesive")
		(11 "B.Adhes" user "B.Adhesive")
		(13 "F.Paste" user "Package Geometry/Pastemask Top")
		(15 "B.Paste" user "Package Geometry/Pastemask Bottom")
		(5 "F.SilkS" user "Ref Des/Silkscreen Top")
		(7 "B.SilkS" user "Ref Des/Silkscreen Bottom")
		(1 "F.Mask" user "Board Geometry/Soldermask Top")
		(3 "B.Mask" user "Board Geometry/Soldermask Bottom")
		(17 "Dwgs.User" user "User.Drawings")
		(19 "Cmts.User" user "User.Comments")
		(21 "Eco1.User" user "User.Eco1")
		(23 "Eco2.User" user "User.Eco2")
		(25 "Edge.Cuts" user "Board Geometry/Outline")
		(27 "Margin" user)
		(31 "F.CrtYd" user "Package Geometry/Place Bound Top")
		(29 "B.CrtYd" user "Package Geometry/Place Bound Bottom")
		(35 "F.Fab" user "Ref Des/Assembly Top")
		(33 "B.Fab" user "Ref Des/Assembly Bottom")
	)
	(footprint ""
		(layer "F.Cu")
		(at 245.7577 -12.954 -90)
		(property "Reference" "C5G1"
			(at 1.848866 0.752348 270)
			(unlocked yes)
			(layer "F.SilkS")
			(effects
				(font
					(size 1.27 0.9652)
					(thickness 0.1524)
				)
			)
		)
		(property "Value" ""
			(at 0 0 270)
			(layer "F.Fab")
			(effects
				(font
					(size 1.27 1.27)
				)
			)
		)
		(duplicate_pad_numbers_are_jumpers no)
		(fp_rect
			(start -0.500126 1.598422)
			(end 0.500126 -0.201422)
			(stroke
				(width 0)
				(type default)
			)
			(fill no)
			(layer "F.CrtYd")
		)
		(fp_line
			(start -0.500126 1.598422)
			(end -0.500126 -0.201422)
			(stroke
				(width 0.1)
				(type default)
			)
			(layer "F.Fab")
		)
		(fp_line
			(start 0.500126 1.598422)
			(end -0.500126 1.598422)
			(stroke
				(width 0.1)
				(type default)
			)
			(layer "F.Fab")
		)
		(fp_line
			(start -0.500126 -0.201422)
			(end 0.500126 -0.201422)
			(stroke
				(width 0.1)
				(type default)
			)
			(layer "F.Fab")
		)
		(fp_line
			(start 0.500126 -0.201422)
			(end 0.500126 1.598422)
			(stroke
				(width 0.1)
				(type default)
			)
			(layer "F.Fab")
		)
		(pad "1" smd rect
			(at 0 0 180)
			(size 0.889 0.9906)
			(layers "F.Cu" "F.Mask" "F.Paste")
			(net "PVDDQ_ABC")
		)
		(pad "2" smd rect
			(at 0 1.397 180)
			(size 0.889 0.9906)
			(layers "F.Cu" "F.Mask" "F.Paste")
			(net "GND")
		)
		(zone
			(layer "F.Cu")
			(hatch none 0.5)
			(connect_pads
				(clearance 0)
			)
			(min_thickness 0.25)
			(keepout
				(tracks allowed)
				(vias not_allowed)
				(pads allowed)
				(copperpour not_allowed)
				(footprints allowed)
			)
			(placement
				(enabled no)
				(sheetname "")
			)
			(fill
				(thermal_gap 0.5)
				(thermal_bridge_width 0.5)
				(island_removal_mode 0)
			)
			(polygon
				(pts
					(xy 244.8052 -13.4493) (xy 244.8052 -12.4587) (xy 245.3132 -12.4587) (xy 245.3132 -13.4493)
				)
			)
		)
		(zone
			(layer "F.Cu")
			(hatch none 0.5)
			(connect_pads
				(clearance 0)
			)
			(min_thickness 0.25)
			(keepout
				(tracks not_allowed)
				(vias allowed)
				(pads allowed)
				(copperpour not_allowed)
				(footprints allowed)
			)
			(placement
				(enabled no)
				(sheetname "")
			)
			(fill
				(thermal_gap 0.5)
				(thermal_bridge_width 0.5)
				(island_removal_mode 0)
			)
			(polygon
				(pts
					(xy 244.8052 -13.4493) (xy 244.8052 -12.4587) (xy 245.3132 -12.4587) (xy 245.3132 -13.4493)
				)
			)
		)
	)
	(footprint ""
		(layer "F.Cu")
		(at 204.089 -106.68 90)
		(property "Reference" "R6N2"
			(at -0.8382 -0.67818 90)
			(unlocked yes)
			(layer "F.SilkS")
			(effects
				(font
					(size 0.4064 0.254)
					(thickness 0.1524)
				)
				(justify left)
			)
		)
		(property "Value" ""
			(at 0 0 90)
			(layer "F.Fab")
			(effects
				(font
					(size 1.27 1.27)
				)
			)
		)
		(duplicate_pad_numbers_are_jumpers no)
		(fp_poly
			(pts
				(xy -0.2794 -0.1016) (xy 0.2794 -0.1016) (xy 0.2794 0.9906) (xy -0.2794 0.9906)
			)
			(stroke
				(width 0)
				(type default)
			)
			(fill no)
			(layer "F.CrtYd")
		)
		(fp_line
			(start 0.2794 -0.1016)
			(end -0.2794 -0.1016)
			(stroke
				(width 0.1)
				(type default)
			)
			(layer "F.Fab")
		)
		(fp_line
			(start -0.2794 -0.1016)
			(end -0.2794 0.9906)
			(stroke
				(width 0.1)
				(type default)
			)
			(layer "F.Fab")
		)
		(fp_line
			(start 0.2794 0.9906)
			(end 0.2794 -0.1016)
			(stroke
				(width 0.1)
				(type default)
			)
			(layer "F.Fab")
		)
		(fp_line
			(start -0.2794 0.9906)
			(end 0.2794 0.9906)
			(stroke
				(width 0.1)
				(type default)
			)
			(layer "F.Fab")
		)
		(pad "1" smd rect
			(at 0 0 90)
			(size 0.508 0.508)
			(layers "F.Cu" "F.Mask" "F.Paste")
			(net "SVID_DIO0_CPU0_R")
		)
		(pad "2" smd rect
			(at 0 0.889 90)
			(size 0.508 0.508)
			(layers "F.Cu" "F.Mask" "F.Paste")
			(net "PVCCIO_CPU0")
		)
		(zone
			(layer "F.Cu")
			(hatch none 0.5)
			(connect_pads
				(clearance 0)
			)
			(min_thickness 0.25)
			(keepout
				(tracks allowed)
				(vias not_allowed)
				(pads allowed)
				(copperpour not_allowed)
				(footprints allowed)
			)
			(placement
				(enabled no)
				(sheetname "")
			)
			(fill
				(thermal_gap 0.5)
				(thermal_bridge_width 0.5)
				(island_removal_mode 0)
			)
			(polygon
				(pts
					(xy 204.343 -106.426) (xy 204.343 -106.934) (xy 204.724 -106.934) (xy 204.724 -106.426)
				)
			)
		)
		(zone
			(layer "F.Cu")
			(hatch none 0.5)
			(connect_pads
				(clearance 0)
			)
			(min_thickness 0.25)
			(keepout
				(tracks not_allowed)
				(vias allowed)
				(pads allowed)
				(copperpour not_allowed)
				(footprints allowed)
			)
			(placement
				(enabled no)
				(sheetname "")
			)
			(fill
				(thermal_gap 0.5)
				(thermal_bridge_width 0.5)
				(island_removal_mode 0)
			)
			(polygon
				(pts
					(xy 204.724 -106.426) (xy 204.724 -106.934) (xy 204.343 -106.934) (xy 204.343 -106.426)
				)
			)
		)
	)
	(footprint ""
		(layer "F.Cu")
		(at 399.770092 0.779526 90)
		(property "Reference" "R8G18"
			(at 0 0 90)
			(layer "F.SilkS")
			(hide yes)
			(effects
				(font
					(size 1.27 1.27)
				)
			)
		)
		(property "Value" ""
			(at 0 0 90)
			(layer "F.Fab")
			(effects
				(font
					(size 1.27 1.27)
				)
			)
		)
		(duplicate_pad_numbers_are_jumpers no)
		(fp_poly
			(pts
				(xy -0.2794 -0.1016) (xy 0.2794 -0.1016) (xy 0.2794 0.9906) (xy -0.2794 0.9906)
			)
			(stroke
				(width 0)
				(type default)
			)
			(fill no)
			(layer "F.CrtYd")
		)
		(fp_line
			(start 0.2794 -0.1016)
			(end -0.2794 -0.1016)
			(stroke
				(width 0.1)
				(type default)
			)
			(layer "F.Fab")
		)
		(fp_line
			(start -0.2794 -0.1016)
			(end -0.2794 0.9906)
			(stroke
				(width 0.1)
				(type default)
			)
			(layer "F.Fab")
		)
		(fp_line
			(start 0.2794 0.9906)
			(end 0.2794 -0.1016)
			(stroke
				(width 0.1)
				(type default)
			)
			(layer "F.Fab")
		)
		(fp_line
			(start -0.2794 0.9906)
			(end 0.2794 0.9906)
			(stroke
				(width 0.1)
				(type default)
			)
			(layer "F.Fab")
		)
		(pad "1" smd rect
			(at 0 0 90)
			(size 0.508 0.508)
			(layers "F.Cu" "F.Mask" "F.Paste")
			(net "JTAG_PLD_TCK")
		)
		(pad "2" smd rect
			(at 0 0.889 90)
			(size 0.508 0.508)
			(layers "F.Cu" "F.Mask" "F.Paste")
			(net "JTAG_PLD_TCK_MUX")
		)
		(zone
			(layer "F.Cu")
			(hatch none 0.5)
			(connect_pads
				(clearance 0)
			)
			(min_thickness 0.25)
			(keepout
				(tracks allowed)
				(vias not_allowed)
				(pads allowed)
				(copperpour not_allowed)
				(footprints allowed)
			)
			(placement
				(enabled no)
				(sheetname "")
			)
			(fill
				(thermal_gap 0.5)
				(thermal_bridge_width 0.5)
				(island_removal_mode 0)
			)
			(polygon
				(pts
					(xy 400.024092 1.033526) (xy 400.024092 0.525526) (xy 400.405092 0.525526) (xy 400.405092 1.033526)
				)
			)
		)
		(zone
			(layer "F.Cu")
			(hatch none 0.5)
			(connect_pads
				(clearance 0)
			)
			(min_thickness 0.25)
			(keepout
				(tracks not_allowed)
				(vias allowed)
				(pads allowed)
				(copperpour not_allowed)
				(footprints allowed)
			)
			(placement
				(enabled no)
				(sheetname "")
			)
			(fill
				(thermal_gap 0.5)
				(thermal_bridge_width 0.5)
				(island_removal_mode 0)
			)
			(polygon
				(pts
					(xy 400.405092 1.033526) (xy 400.405092 0.525526) (xy 400.024092 0.525526) (xy 400.024092 1.033526)
				)
			)
		)
	)
	(footprint ""
		(layer "F.Cu")
		(at 13.462 -50.927 90)
		(property "Reference" "C1E17"
			(at 0 0 90)
			(layer "F.SilkS")
			(hide yes)
			(effects
				(font
					(size 1.27 1.27)
				)
			)
		)
		(property "Value" ""
			(at 0 0 90)
			(layer "F.Fab")
			(effects
				(font
					(size 1.27 1.27)
				)
			)
		)
		(duplicate_pad_numbers_are_jumpers no)
		(fp_rect
			(start -0.3048 -0.1016)
			(end 0.3048 0.9906)
			(stroke
				(width 0)
				(type default)
			)
			(fill no)
			(layer "F.CrtYd")
		)
		(fp_line
			(start 0.3048 -0.1016)
			(end -0.3048 -0.1016)
			(stroke
				(width 0.1)
				(type default)
			)
			(layer "F.Fab")
		)
		(fp_line
			(start -0.3048 -0.1016)
			(end -0.3048 0.9906)
			(stroke
				(width 0.1)
				(type default)
			)
			(layer "F.Fab")
		)
		(fp_line
			(start 0.3048 0.9906)
			(end 0.3048 -0.1016)
			(stroke
				(width 0.1)
				(type default)
			)
			(layer "F.Fab")
		)
		(fp_line
			(start -0.3048 0.9906)
			(end 0.3048 0.9906)
			(stroke
				(width 0.1)
				(type default)
			)
			(layer "F.Fab")
		)
		(pad "1" smd rect
			(at 0 0 90)
			(size 0.508 0.508)
			(layers "F.Cu" "F.Mask" "F.Paste")
			(net "P12V_PSU")
		)
		(pad "2" smd rect
			(at 0 0.889 90)
			(size 0.508 0.508)
			(layers "F.Cu" "F.Mask" "F.Paste")
			(net "GND")
		)
		(zone
			(layer "F.Cu")
			(hatch none 0.5)
			(connect_pads
				(clearance 0)
			)
			(min_thickness 0.25)
			(keepout
				(tracks allowed)
				(vias not_allowed)
				(pads allowed)
				(copperpour not_allowed)
				(footprints allowed)
			)
			(placement
				(enabled no)
				(sheetname "")
			)
			(fill
				(thermal_gap 0.5)
				(thermal_bridge_width 0.5)
				(island_removal_mode 0)
			)
			(polygon
				(pts
					(xy 13.716 -50.673) (xy 14.097 -50.673) (xy 14.097 -51.181) (xy 13.716 -51.181)
				)
			)
		)
		(zone
			(layer "F.Cu")
			(hatch none 0.5)
			(connect_pads
				(clearance 0)
			)
			(min_thickness 0.25)
			(keepout
				(tracks not_allowed)
				(vias allowed)
				(pads allowed)
				(copperpour not_allowed)
				(footprints allowed)
			)
			(placement
				(enabled no)
				(sheetname "")
			)
			(fill
				(thermal_gap 0.5)
				(thermal_bridge_width 0.5)
				(island_removal_mode 0)
			)
			(polygon
				(pts
					(xy 13.716 -50.673) (xy 14.097 -50.673) (xy 14.097 -51.181) (xy 13.716 -51.181)
				)
			)
		)
	)
	(footprint ""
		(layer "F.Cu")
		(at 19.195288 -4.574032 -90)
		(property "Reference" "C1G17"
			(at 0 0 270)
			(layer "F.SilkS")
			(hide yes)
			(effects
				(font
					(size 1.27 1.27)
				)
			)
		)
		(property "Value" ""
			(at 0 0 270)
			(layer "F.Fab")
			(effects
				(font
					(size 1.27 1.27)
				)
			)
		)
		(duplicate_pad_numbers_are_jumpers no)
		(fp_poly
			(pts
				(xy -0.7239 -0.2159) (xy 0.7239 -0.2159) (xy 0.7239 1.9939) (xy -0.7239 1.9939)
			)
			(stroke
				(width 0)
				(type default)
			)
			(fill no)
			(layer "F.CrtYd")
		)
		(fp_line
			(start -0.7239 1.9939)
			(end 0.7239 1.9939)
			(stroke
				(width 0.1)
				(type default)
			)
			(layer "F.Fab")
		)
		(fp_line
			(start 0.7239 1.9939)
			(end 0.7239 -0.2159)
			(stroke
				(width 0.1)
				(type default)
			)
			(layer "F.Fab")
		)
		(fp_line
			(start -0.7239 -0.2159)
			(end -0.7239 1.9939)
			(stroke
				(width 0.1)
				(type default)
			)
			(layer "F.Fab")
		)
		(fp_line
			(start 0.7239 -0.2159)
			(end -0.7239 -0.2159)
			(stroke
				(width 0.1)
				(type default)
			)
			(layer "F.Fab")
		)
		(pad "1" smd rect
			(at 0 0 270)
			(size 1.27 1.016)
			(layers "F.Cu" "F.Mask" "F.Paste")
			(net "PVDDQ_GHJ")
		)
		(pad "2" smd rect
			(at 0 1.778 270)
			(size 1.27 1.016)
			(layers "F.Cu" "F.Mask" "F.Paste")
			(net "GND")
		)
		(zone
			(layer "F.Cu")
			(hatch none 0.5)
			(connect_pads
				(clearance 0)
			)
			(min_thickness 0.25)
			(keepout
				(tracks not_allowed)
				(vias allowed)
				(pads allowed)
				(copperpour not_allowed)
				(footprints allowed)
			)
			(placement
				(enabled no)
				(sheetname "")
			)
			(fill
				(thermal_gap 0.5)
				(thermal_bridge_width 0.5)
				(island_removal_mode 0)
			)
			(polygon
				(pts
					(xy 18.687288 -5.209032) (xy 18.687288 -3.939032) (xy 17.925288 -3.939032) (xy 17.925288 -5.209032)
				)
			)
		)
	)
	(footprint ""
		(layer "F.Cu")
		(at 7.238746 -109.65307 90)
		(property "Reference" "C9M4"
			(at 0 0 90)
			(layer "F.SilkS")
			(hide yes)
			(effects
				(font
					(size 1.27 1.27)
				)
			)
		)
		(property "Value" ""
			(at 0 0 90)
			(layer "F.Fab")
			(effects
				(font
					(size 1.27 1.27)
				)
			)
		)
		(duplicate_pad_numbers_are_jumpers no)
		(fp_poly
			(pts
				(xy -0.7239 -0.2159) (xy 0.7239 -0.2159) (xy 0.7239 1.9939) (xy -0.7239 1.9939)
			)
			(stroke
				(width 0)
				(type default)
			)
			(fill no)
			(layer "F.CrtYd")
		)
		(fp_line
			(start 0.7239 -0.2159)
			(end -0.7239 -0.2159)
			(stroke
				(width 0.1)
				(type default)
			)
			(layer "F.Fab")
		)
		(fp_line
			(start -0.7239 -0.2159)
			(end -0.7239 1.9939)
			(stroke
				(width 0.1)
				(type default)
			)
			(layer "F.Fab")
		)
		(fp_line
			(start 0.7239 1.9939)
			(end 0.7239 -0.2159)
			(stroke
				(width 0.1)
				(type default)
			)
			(layer "F.Fab")
		)
		(fp_line
			(start -0.7239 1.9939)
			(end 0.7239 1.9939)
			(stroke
				(width 0.1)
				(type default)
			)
			(layer "F.Fab")
		)
		(pad "1" smd rect
			(at 0 0 90)
			(size 1.27 1.016)
			(layers "F.Cu" "F.Mask" "F.Paste")
			(net "P12V_FAN")
		)
		(pad "2" smd rect
			(at 0 1.778 90)
			(size 1.27 1.016)
			(layers "F.Cu" "F.Mask" "F.Paste")
			(net "GND")
		)
		(zone
			(layer "F.Cu")
			(hatch none 0.5)
			(connect_pads
				(clearance 0)
			)
			(min_thickness 0.25)
			(keepout
				(tracks not_allowed)
				(vias allowed)
				(pads allowed)
				(copperpour not_allowed)
				(footprints allowed)
			)
			(placement
				(enabled no)
				(sheetname "")
			)
			(fill
				(thermal_gap 0.5)
				(thermal_bridge_width 0.5)
				(island_removal_mode 0)
			)
			(polygon
				(pts
					(xy 7.746746 -109.01807) (xy 7.746746 -110.28807) (xy 8.508746 -110.28807) (xy 8.508746 -109.01807)
				)
			)
		)
	)
	(footprint ""
		(layer "F.Cu")
		(at 166.37 -70.6374 180)
		(property "Reference" "R4D46"
			(at 0 0 180)
			(layer "F.SilkS")
			(hide yes)
			(effects
				(font
					(size 1.27 1.27)
				)
			)
		)
		(property "Value" ""
			(at 0 0 180)
			(layer "F.Fab")
			(effects
				(font
					(size 1.27 1.27)
				)
			)
		)
		(duplicate_pad_numbers_are_jumpers no)
		(fp_poly
			(pts
				(xy -0.2794 -0.1016) (xy 0.2794 -0.1016) (xy 0.2794 0.9906) (xy -0.2794 0.9906)
			)
			(stroke
				(width 0)
				(type default)
			)
			(fill no)
			(layer "F.CrtYd")
		)
		(fp_line
			(start 0.2794 0.9906)
			(end 0.2794 -0.1016)
			(stroke
				(width 0.1)
				(type default)
			)
			(layer "F.Fab")
		)
		(fp_line
			(start 0.2794 -0.1016)
			(end -0.2794 -0.1016)
			(stroke
				(width 0.1)
				(type default)
			)
			(layer "F.Fab")
		)
		(fp_line
			(start -0.2794 0.9906)
			(end 0.2794 0.9906)
			(stroke
				(width 0.1)
				(type default)
			)
			(layer "F.Fab")
		)
		(fp_line
			(start -0.2794 -0.1016)
			(end -0.2794 0.9906)
			(stroke
				(width 0.1)
				(type default)
			)
			(layer "F.Fab")
		)
		(pad "1" smd rect
			(at 0 0 180)
			(size 0.508 0.508)
			(layers "F.Cu" "F.Mask" "F.Paste")
			(net "PWRGD_PVCCIO_CPU1_R")
		)
		(pad "2" smd rect
			(at 0 0.889 180)
			(size 0.508 0.508)
			(layers "F.Cu" "F.Mask" "F.Paste")
			(net "PWRGD_PVCCIO_CPU1")
		)
		(zone
			(layer "F.Cu")
			(hatch none 0.5)
			(connect_pads
				(clearance 0)
			)
			(min_thickness 0.25)
			(keepout
				(tracks not_allowed)
				(vias allowed)
				(pads allowed)
				(copperpour not_allowed)
				(footprints allowed)
			)
			(placement
				(enabled no)
				(sheetname "")
			)
			(fill
				(thermal_gap 0.5)
				(thermal_bridge_width 0.5)
				(island_removal_mode 0)
			)
			(polygon
				(pts
					(xy 166.624 -71.2724) (xy 166.116 -71.2724) (xy 166.116 -70.8914) (xy 166.624 -70.8914)
				)
			)
		)
		(zone
			(layer "F.Cu")
			(hatch none 0.5)
			(connect_pads
				(clearance 0)
			)
			(min_thickness 0.25)
			(keepout
				(tracks allowed)
				(vias not_allowed)
				(pads allowed)
				(copperpour not_allowed)
				(footprints allowed)
			)
			(placement
				(enabled no)
				(sheetname "")
			)
			(fill
				(thermal_gap 0.5)
				(thermal_bridge_width 0.5)
				(island_removal_mode 0)
			)
			(polygon
				(pts
					(xy 166.624 -70.8914) (xy 166.116 -70.8914) (xy 166.116 -71.2724) (xy 166.624 -71.2724)
				)
			)
		)
	)
	(footprint ""
		(layer "F.Cu")
		(at 101.92004 -73.318116)
		(property "Reference" "C2D37"
			(at 0 0 0)
			(layer "F.SilkS")
			(hide yes)
			(effects
				(font
					(size 1.27 1.27)
				)
			)
		)
		(property "Value" ""
			(at 0 0 0)
			(layer "F.Fab")
			(effects
				(font
					(size 1.27 1.27)
				)
			)
		)
		(duplicate_pad_numbers_are_jumpers no)
		(fp_poly
			(pts
				(xy -0.4953 -0.2032) (xy 0.4953 -0.2032) (xy 0.4953 1.6002) (xy -0.4953 1.6002)
			)
			(stroke
				(width 0)
				(type default)
			)
			(fill no)
			(layer "F.CrtYd")
		)
		(fp_line
			(start -0.4953 -0.2032)
			(end 0.4953 -0.2032)
			(stroke
				(width 0.1)
				(type default)
			)
			(layer "F.Fab")
		)
		(fp_line
			(start -0.4953 1.6002)
			(end -0.4953 -0.2032)
			(stroke
				(width 0.1)
				(type default)
			)
			(layer "F.Fab")
		)
		(fp_line
			(start 0.4953 -0.2032)
			(end 0.4953 1.6002)
			(stroke
				(width 0.1)
				(type default)
			)
			(layer "F.Fab")
		)
		(fp_line
			(start 0.4953 1.6002)
			(end -0.4953 1.6002)
			(stroke
				(width 0.1)
				(type default)
			)
			(layer "F.Fab")
		)
		(pad "1" smd rect
			(at 0 0)
			(size 0.762 0.889)
			(layers "F.Cu" "F.Mask" "F.Paste")
			(net "PVCCIN_CPU1")
		)
		(pad "2" smd rect
			(at 0 1.397)
			(size 0.762 0.889)
			(layers "F.Cu" "F.Mask" "F.Paste")
			(net "GND")
		)
		(zone
			(layer "F.Cu")
			(hatch none 0.5)
			(connect_pads
				(clearance 0)
			)
			(min_thickness 0.25)
			(keepout
				(tracks not_allowed)
				(vias allowed)
				(pads allowed)
				(copperpour not_allowed)
				(footprints allowed)
			)
			(placement
				(enabled no)
				(sheetname "")
			)
			(fill
				(thermal_gap 0.5)
				(thermal_bridge_width 0.5)
				(island_removal_mode 0)
			)
			(polygon
				(pts
					(xy 101.53904 -72.873616) (xy 102.30104 -72.873616) (xy 102.30104 -72.365616) (xy 101.53904 -72.365616)
				)
			)
		)
	)
)
